# S9S_MB_2U (Grand Teton) — schematic netlist excerpt (pin names and nets, part order shuffled) for the footprints in the layout excerpt that follows; sources: Cadence DE-HDL packaged netlist, KiCad conversion of 03242023_DA0F0TMBIJ0_F0T_Motherboard_J_brd_V01_OCP.brd

PC557  Q_CAP  2.2UF 10V 10% X6S  pkg C0402  page 285 : A = PVCCIN_CPU1_VDD1 ; B = GND
R2848  Q_RES  0 5% CHIP  pkg 0402LF  page 227 : A = RST_SWB_BIC_N ; B = RST_SWB_BIC_R_N

(kicad_pcb
	(version 20260206)
	(generator "pcbnew")
	(generator_version "10.0")
	(general
		(thickness 1.6)
		(legacy_teardrops no)
	)
	(paper "A4")
	(title_block
		(title "03242023_DA0F0TMBIJ0_F0T_Motherboard_J_brd_V01_OCP.brd")
		(comment 1 "Grand Teton / footprints 3960-3961 of 6105")
	)
	(layers
		(0 "F.Cu" signal "TOP")
		(4 "In1.Cu" signal "GND")
		(6 "In2.Cu" signal "IN1")
		(8 "In3.Cu" signal "GND1")
		(10 "In4.Cu" signal "IN2")
		(12 "In5.Cu" signal "GND2")
		(14 "In6.Cu" signal "IN3")
		(16 "In7.Cu" signal "GND3")
		(18 "In8.Cu" signal "VCC")
		(20 "In9.Cu" signal "VCC1")
		(22 "In10.Cu" signal "GND4")
		(24 "In11.Cu" signal "IN4")
		(26 "In12.Cu" signal "GND5")
		(28 "In13.Cu" signal "IN5")
		(30 "In14.Cu" signal "GND6")
		(32 "In15.Cu" signal "IN6")
		(34 "In16.Cu" signal "GND7")
		(2 "B.Cu" signal "BOTTOM")
		(9 "F.Adhes" user "F.Adhesive")
		(11 "B.Adhes" user "B.Adhesive")
		(13 "F.Paste" user "Package Geometry/Pastemask Top")
		(15 "B.Paste" user "Package Geometry/Pastemask Bottom")
		(5 "F.SilkS" user "Ref Des/Silkscreen Top")
		(7 "B.SilkS" user "Ref Des/Silkscreen Bottom")
		(1 "F.Mask" user "Board Geometry/Soldermask Top")
		(3 "B.Mask" user "Board Geometry/Soldermask Bottom")
		(17 "Dwgs.User" user "User.Drawings")
		(19 "Cmts.User" user "User.Comments")
		(21 "Eco1.User" user "User.Eco1")
		(23 "Eco2.User" user "User.Eco2")
		(25 "Edge.Cuts" user "Board Geometry/Outline")
		(27 "Margin" user)
		(31 "F.CrtYd" user "Package Geometry/Place Bound Top")
		(29 "B.CrtYd" user "Package Geometry/Place Bound Bottom")
		(35 "F.Fab" user "Ref Des/Assembly Top")
		(33 "B.Fab" user "Ref Des/Assembly Bottom")
	)
	(footprint ""
		(layer "F.Cu")
		(at 93.422978 -336.192368 90)
		(property "Reference" "PC557"
			(at 0 0 90)
			(layer "F.SilkS")
			(hide yes)
			(effects
				(font
					(size 1.27 1.27)
				)
			)
		)
		(property "Value" ""
			(at 0 0 90)
			(layer "F.Fab")
			(effects
				(font
					(size 1.27 1.27)
				)
			)
		)
		(duplicate_pad_numbers_are_jumpers no)
		(fp_line
			(start 0.7874 -0.4064)
			(end 0.7874 0.4064)
			(stroke
				(width 0.1524)
				(type default)
			)
			(layer "F.SilkS")
		)
		(fp_line
			(start -0.7874 -0.4064)
			(end 0.7874 -0.4064)
			(stroke
				(width 0.1524)
				(type default)
			)
			(layer "F.SilkS")
		)
		(fp_line
			(start 0.7874 0.4064)
			(end -0.7874 0.4064)
			(stroke
				(width 0.1524)
				(type default)
			)
			(layer "F.SilkS")
		)
		(fp_line
			(start -0.7874 0.4064)
			(end -0.7874 -0.4064)
			(stroke
				(width 0.1524)
				(type default)
			)
			(layer "F.SilkS")
		)
		(fp_line
			(start -0.12065 -0.305054)
			(end -0.12065 -0.2794)
			(stroke
				(width 0.1)
				(type default)
			)
			(layer "F.Fab")
		)
		(fp_line
			(start -0.67945 -0.305054)
			(end -0.12065 -0.305054)
			(stroke
				(width 0.1)
				(type default)
			)
			(layer "F.Fab")
		)
		(fp_line
			(start 0.67945 -0.3048)
			(end 0.67945 0.3048)
			(stroke
				(width 0.1)
				(type default)
			)
			(layer "F.Fab")
		)
		(fp_line
			(start 0.12065 -0.3048)
			(end 0.67945 -0.3048)
			(stroke
				(width 0.1)
				(type default)
			)
			(layer "F.Fab")
		)
		(fp_line
			(start 0.12065 -0.2794)
			(end 0.12065 -0.3048)
			(stroke
				(width 0.1)
				(type default)
			)
			(layer "F.Fab")
		)
		(fp_line
			(start -0.12065 -0.2794)
			(end 0.12065 -0.2794)
			(stroke
				(width 0.1)
				(type default)
			)
			(layer "F.Fab")
		)
		(fp_line
			(start 0.120396 0.2794)
			(end -0.12065 0.2794)
			(stroke
				(width 0.1)
				(type default)
			)
			(layer "F.Fab")
		)
		(fp_line
			(start -0.12065 0.2794)
			(end -0.12065 0.3048)
			(stroke
				(width 0.1)
				(type default)
			)
			(layer "F.Fab")
		)
		(fp_line
			(start 0.67945 0.3048)
			(end 0.120396 0.3048)
			(stroke
				(width 0.1)
				(type default)
			)
			(layer "F.Fab")
		)
		(fp_line
			(start 0.120396 0.3048)
			(end 0.120396 0.2794)
			(stroke
				(width 0.1)
				(type default)
			)
			(layer "F.Fab")
		)
		(fp_line
			(start -0.12065 0.3048)
			(end -0.67945 0.3048)
			(stroke
				(width 0.1)
				(type default)
			)
			(layer "F.Fab")
		)
		(fp_line
			(start -0.67945 0.3048)
			(end -0.67945 -0.305054)
			(stroke
				(width 0.1)
				(type default)
			)
			(layer "F.Fab")
		)
		(pad "1" smd circle
			(at -0.40005 0 90)
			(size 0 0)
			(layers "F.Cu" "F.Mask" "F.Paste")
			(net "PVCCIN_CPU1_VDD1")
		)
		(pad "2" smd circle
			(at 0.40005 0 90)
			(size 0 0)
			(layers "F.Cu" "F.Mask" "F.Paste")
			(net "GND")
		)
	)
	(footprint ""
		(layer "F.Cu")
		(at 17.864582 -410.802836 -90)
		(property "Reference" "R2848"
			(at 0 0 270)
			(layer "F.SilkS")
			(hide yes)
			(effects
				(font
					(size 1.27 1.27)
				)
			)
		)
		(property "Value" ""
			(at 0 0 270)
			(layer "F.Fab")
			(effects
				(font
					(size 1.27 1.27)
				)
			)
		)
		(duplicate_pad_numbers_are_jumpers no)
		(fp_line
			(start -0.7874 0.4064)
			(end -0.7874 -0.4064)
			(stroke
				(width 0.1524)
				(type default)
			)
			(layer "F.SilkS")
		)
		(fp_line
			(start 0.7874 0.4064)
			(end -0.7874 0.4064)
			(stroke
				(width 0.1524)
				(type default)
			)
			(layer "F.SilkS")
		)
		(fp_line
			(start -0.7874 -0.4064)
			(end 0.7874 -0.4064)
			(stroke
				(width 0.1524)
				(type default)
			)
			(layer "F.SilkS")
		)
		(fp_line
			(start 0.7874 -0.4064)
			(end 0.7874 0.4064)
			(stroke
				(width 0.1524)
				(type default)
			)
			(layer "F.SilkS")
		)
		(fp_line
			(start -0.67945 0.3048)
			(end -0.67945 -0.305054)
			(stroke
				(width 0.1)
				(type default)
			)
			(layer "F.Fab")
		)
		(fp_line
			(start -0.12065 0.3048)
			(end -0.67945 0.3048)
			(stroke
				(width 0.1)
				(type default)
			)
			(layer "F.Fab")
		)
		(fp_line
			(start 0.120396 0.3048)
			(end 0.120396 0.2794)
			(stroke
				(width 0.1)
				(type default)
			)
			(layer "F.Fab")
		)
		(fp_line
			(start 0.67945 0.3048)
			(end 0.120396 0.3048)
			(stroke
				(width 0.1)
				(type default)
			)
			(layer "F.Fab")
		)
		(fp_line
			(start -0.12065 0.2794)
			(end -0.12065 0.3048)
			(stroke
				(width 0.1)
				(type default)
			)
			(layer "F.Fab")
		)
		(fp_line
			(start 0.120396 0.2794)
			(end -0.12065 0.2794)
			(stroke
				(width 0.1)
				(type default)
			)
			(layer "F.Fab")
		)
		(fp_line
			(start -0.12065 -0.2794)
			(end 0.12065 -0.2794)
			(stroke
				(width 0.1)
				(type default)
			)
			(layer "F.Fab")
		)
		(fp_line
			(start 0.12065 -0.2794)
			(end 0.12065 -0.3048)
			(stroke
				(width 0.1)
				(type default)
			)
			(layer "F.Fab")
		)
		(fp_line
			(start 0.12065 -0.3048)
			(end 0.67945 -0.3048)
			(stroke
				(width 0.1)
				(type default)
			)
			(layer "F.Fab")
		)
		(fp_line
			(start 0.67945 -0.3048)
			(end 0.67945 0.3048)
			(stroke
				(width 0.1)
				(type default)
			)
			(layer "F.Fab")
		)
		(fp_line
			(start -0.67945 -0.305054)
			(end -0.12065 -0.305054)
			(stroke
				(width 0.1)
				(type default)
			)
			(layer "F.Fab")
		)
		(fp_line
			(start -0.12065 -0.305054)
			(end -0.12065 -0.2794)
			(stroke
				(width 0.1)
				(type default)
			)
			(layer "F.Fab")
		)
		(pad "1" smd circle
			(at -0.40005 0 270)
			(size 0 0)
			(layers "F.Cu" "F.Mask" "F.Paste")
			(net "RST_SWB_BIC_N")
		)
		(pad "2" smd circle
			(at 0.40005 0 270)
			(size 0 0)
			(layers "F.Cu" "F.Mask" "F.Paste")
			(net "RST_SWB_BIC_R_N")
		)
	)
)
